# T6G (Grand Teton) — schematic netlist excerpt (pin names and nets, part order shuffled) for the footprints in the layout excerpt that follows; sources: Cadence DE-HDL packaged netlist, KiCad conversion of 04192023_DAF0TMB3IC0_F0TG_MB_C_brd_V02_OCP.brd

C203  Q_CAP  1UF 4V 20% X6S  pkg 0201  page 334 : A = P1V8_CPU1_RT1_1A_1D ; B = GND
R504  Q_RES  15 1% CHIP  pkg 0402LF  page 41 : A = M_E_CPU1_ALERT_N ; B = M_E_CPU1_ALERT_R_N
R532  Q_RES  2.2K 5% CHIP  pkg 0402LF  page 54 : A = CPU1_BP1 ; B = PVDD18_S5_P1

(kicad_pcb
	(version 20260206)
	(generator "pcbnew")
	(generator_version "10.0")
	(general
		(thickness 1.6)
		(legacy_teardrops no)
	)
	(paper "A4")
	(title_block
		(title "04192023_DAF0TMB3IC0_F0TG_MB_C_brd_V02_OCP.brd")
		(comment 1 "Grand Teton / footprints 7169-7171 of 8354")
	)
	(layers
		(0 "F.Cu" signal "TOP")
		(4 "In1.Cu" signal "GND")
		(6 "In2.Cu" signal "IN1")
		(8 "In3.Cu" signal "GND1")
		(10 "In4.Cu" signal "IN2")
		(12 "In5.Cu" signal "GND2")
		(14 "In6.Cu" signal "IN3")
		(16 "In7.Cu" signal "GND3")
		(18 "In8.Cu" signal "VCC")
		(20 "In9.Cu" signal "VCC1")
		(22 "In10.Cu" signal "GND4")
		(24 "In11.Cu" signal "IN4")
		(26 "In12.Cu" signal "GND5")
		(28 "In13.Cu" signal "IN5")
		(30 "In14.Cu" signal "GND6")
		(32 "In15.Cu" signal "IN6")
		(34 "In16.Cu" signal "GND7")
		(2 "B.Cu" signal "BOTTOM")
		(9 "F.Adhes" user "F.Adhesive")
		(11 "B.Adhes" user "B.Adhesive")
		(13 "F.Paste" user "Package Geometry/Pastemask Top")
		(15 "B.Paste" user "Package Geometry/Pastemask Bottom")
		(5 "F.SilkS" user "Ref Des/Silkscreen Top")
		(7 "B.SilkS" user "Ref Des/Silkscreen Bottom")
		(1 "F.Mask" user "Board Geometry/Soldermask Top")
		(3 "B.Mask" user "Board Geometry/Soldermask Bottom")
		(17 "Dwgs.User" user "User.Drawings")
		(19 "Cmts.User" user "User.Comments")
		(21 "Eco1.User" user "User.Eco1")
		(23 "Eco2.User" user "User.Eco2")
		(25 "Edge.Cuts" user "Board Geometry/Outline")
		(27 "Margin" user)
		(31 "F.CrtYd" user "Package Geometry/Place Bound Top")
		(29 "B.CrtYd" user "Package Geometry/Place Bound Bottom")
		(35 "F.Fab" user "Ref Des/Assembly Top")
		(33 "B.Fab" user "Ref Des/Assembly Bottom")
	)
	(footprint ""
		(layer "B.Cu")
		(at 30.249114 -244.085364 180)
		(property "Reference" "R504"
			(at 0 0 0)
			(layer "B.SilkS")
			(hide yes)
			(effects
				(font
					(size 1.27 1.27)
				)
				(justify mirror)
			)
		)
		(property "Value" ""
			(at 0 0 0)
			(layer "B.Fab")
			(effects
				(font
					(size 1.27 1.27)
				)
				(justify mirror)
			)
		)
		(duplicate_pad_numbers_are_jumpers no)
		(fp_line
			(start 0.7874 0.4064)
			(end 0.7874 -0.4064)
			(stroke
				(width 0.1524)
				(type default)
			)
			(layer "B.SilkS")
		)
		(fp_line
			(start 0.7874 -0.4064)
			(end -0.7874 -0.4064)
			(stroke
				(width 0.1524)
				(type default)
			)
			(layer "B.SilkS")
		)
		(fp_line
			(start -0.7874 0.4064)
			(end 0.7874 0.4064)
			(stroke
				(width 0.1524)
				(type default)
			)
			(layer "B.SilkS")
		)
		(fp_line
			(start -0.7874 -0.4064)
			(end -0.7874 0.4064)
			(stroke
				(width 0.1524)
				(type default)
			)
			(layer "B.SilkS")
		)
		(fp_line
			(start 0.67945 0.3048)
			(end 0.67945 -0.305054)
			(stroke
				(width 0.1)
				(type default)
			)
			(layer "B.Fab")
		)
		(fp_line
			(start 0.67945 -0.305054)
			(end 0.12065 -0.305054)
			(stroke
				(width 0.1)
				(type default)
			)
			(layer "B.Fab")
		)
		(fp_line
			(start 0.12065 0.3048)
			(end 0.67945 0.3048)
			(stroke
				(width 0.1)
				(type default)
			)
			(layer "B.Fab")
		)
		(fp_line
			(start 0.12065 0.2794)
			(end 0.12065 0.3048)
			(stroke
				(width 0.1)
				(type default)
			)
			(layer "B.Fab")
		)
		(fp_line
			(start 0.12065 -0.2794)
			(end -0.12065 -0.2794)
			(stroke
				(width 0.1)
				(type default)
			)
			(layer "B.Fab")
		)
		(fp_line
			(start 0.12065 -0.305054)
			(end 0.12065 -0.2794)
			(stroke
				(width 0.1)
				(type default)
			)
			(layer "B.Fab")
		)
		(fp_line
			(start -0.120396 0.3048)
			(end -0.120396 0.2794)
			(stroke
				(width 0.1)
				(type default)
			)
			(layer "B.Fab")
		)
		(fp_line
			(start -0.120396 0.2794)
			(end 0.12065 0.2794)
			(stroke
				(width 0.1)
				(type default)
			)
			(layer "B.Fab")
		)
		(fp_line
			(start -0.12065 -0.2794)
			(end -0.12065 -0.3048)
			(stroke
				(width 0.1)
				(type default)
			)
			(layer "B.Fab")
		)
		(fp_line
			(start -0.12065 -0.3048)
			(end -0.67945 -0.3048)
			(stroke
				(width 0.1)
				(type default)
			)
			(layer "B.Fab")
		)
		(fp_line
			(start -0.67945 0.3048)
			(end -0.120396 0.3048)
			(stroke
				(width 0.1)
				(type default)
			)
			(layer "B.Fab")
		)
		(fp_line
			(start -0.67945 -0.3048)
			(end -0.67945 0.3048)
			(stroke
				(width 0.1)
				(type default)
			)
			(layer "B.Fab")
		)
		(pad "1" smd circle
			(at 0.40005 0)
			(size 0 0)
			(layers "B.Cu" "B.Mask" "B.Paste")
			(net "M_E_CPU1_ALERT_N")
		)
		(pad "2" smd circle
			(at -0.40005 0)
			(size 0 0)
			(layers "B.Cu" "B.Mask" "B.Paste")
			(net "M_E_CPU1_ALERT_R_N")
		)
	)
	(footprint ""
		(layer "B.Cu")
		(at 94.948502 -205.14945 90)
		(property "Reference" "R532"
			(at 0 0 90)
			(layer "B.SilkS")
			(hide yes)
			(effects
				(font
					(size 1.27 1.27)
				)
				(justify mirror)
			)
		)
		(property "Value" ""
			(at 0 0 90)
			(layer "B.Fab")
			(effects
				(font
					(size 1.27 1.27)
				)
				(justify mirror)
			)
		)
		(duplicate_pad_numbers_are_jumpers no)
		(fp_line
			(start 0.7874 -0.4064)
			(end -0.7874 -0.4064)
			(stroke
				(width 0.1524)
				(type default)
			)
			(layer "B.SilkS")
		)
		(fp_line
			(start -0.7874 -0.4064)
			(end -0.7874 0.4064)
			(stroke
				(width 0.1524)
				(type default)
			)
			(layer "B.SilkS")
		)
		(fp_line
			(start 0.7874 0.4064)
			(end 0.7874 -0.4064)
			(stroke
				(width 0.1524)
				(type default)
			)
			(layer "B.SilkS")
		)
		(fp_line
			(start -0.7874 0.4064)
			(end 0.7874 0.4064)
			(stroke
				(width 0.1524)
				(type default)
			)
			(layer "B.SilkS")
		)
		(fp_line
			(start 0.67945 -0.305054)
			(end 0.12065 -0.305054)
			(stroke
				(width 0.1)
				(type default)
			)
			(layer "B.Fab")
		)
		(fp_line
			(start 0.12065 -0.305054)
			(end 0.12065 -0.2794)
			(stroke
				(width 0.1)
				(type default)
			)
			(layer "B.Fab")
		)
		(fp_line
			(start -0.12065 -0.3048)
			(end -0.67945 -0.3048)
			(stroke
				(width 0.1)
				(type default)
			)
			(layer "B.Fab")
		)
		(fp_line
			(start -0.67945 -0.3048)
			(end -0.67945 0.3048)
			(stroke
				(width 0.1)
				(type default)
			)
			(layer "B.Fab")
		)
		(fp_line
			(start 0.12065 -0.2794)
			(end -0.12065 -0.2794)
			(stroke
				(width 0.1)
				(type default)
			)
			(layer "B.Fab")
		)
		(fp_line
			(start -0.12065 -0.2794)
			(end -0.12065 -0.3048)
			(stroke
				(width 0.1)
				(type default)
			)
			(layer "B.Fab")
		)
		(fp_line
			(start 0.12065 0.2794)
			(end 0.12065 0.3048)
			(stroke
				(width 0.1)
				(type default)
			)
			(layer "B.Fab")
		)
		(fp_line
			(start -0.120396 0.2794)
			(end 0.12065 0.2794)
			(stroke
				(width 0.1)
				(type default)
			)
			(layer "B.Fab")
		)
		(fp_line
			(start 0.67945 0.3048)
			(end 0.67945 -0.305054)
			(stroke
				(width 0.1)
				(type default)
			)
			(layer "B.Fab")
		)
		(fp_line
			(start 0.12065 0.3048)
			(end 0.67945 0.3048)
			(stroke
				(width 0.1)
				(type default)
			)
			(layer "B.Fab")
		)
		(fp_line
			(start -0.120396 0.3048)
			(end -0.120396 0.2794)
			(stroke
				(width 0.1)
				(type default)
			)
			(layer "B.Fab")
		)
		(fp_line
			(start -0.67945 0.3048)
			(end -0.120396 0.3048)
			(stroke
				(width 0.1)
				(type default)
			)
			(layer "B.Fab")
		)
		(pad "1" smd circle
			(at 0.40005 0 270)
			(size 0 0)
			(layers "B.Cu" "B.Mask" "B.Paste")
			(net "CPU1_BP1")
		)
		(pad "2" smd circle
			(at -0.40005 0 270)
			(size 0 0)
			(layers "B.Cu" "B.Mask" "B.Paste")
			(net "PVDD18_S5_P1")
		)
	)
	(footprint ""
		(layer "B.Cu")
		(at 90.706194 -386.766562 90)
		(property "Reference" "C203"
			(at 0 0 90)
			(layer "B.SilkS")
			(hide yes)
			(effects
				(font
					(size 1.27 1.27)
				)
				(justify mirror)
			)
		)
		(property "Value" ""
			(at 0 0 90)
			(layer "B.Fab")
			(effects
				(font
					(size 1.27 1.27)
				)
				(justify mirror)
			)
		)
		(duplicate_pad_numbers_are_jumpers no)
		(fp_line
			(start 0.299974 -0.150114)
			(end -0.299974 -0.150114)
			(stroke
				(width 0.1)
				(type default)
			)
			(layer "B.Fab")
		)
		(fp_line
			(start -0.299974 -0.150114)
			(end -0.299974 0.150114)
			(stroke
				(width 0.1)
				(type default)
			)
			(layer "B.Fab")
		)
		(fp_line
			(start 0.299974 0.150114)
			(end 0.299974 -0.150114)
			(stroke
				(width 0.1)
				(type default)
			)
			(layer "B.Fab")
		)
		(fp_line
			(start -0.299974 0.150114)
			(end 0.299974 0.150114)
			(stroke
				(width 0.1)
				(type default)
			)
			(layer "B.Fab")
		)
		(pad "1" smd rect
			(at 0.2667 0 270)
			(size 0.3048 0.381)
			(layers "B.Cu" "B.Mask" "B.Paste")
			(net "P1V8_CPU1_RT1_1A_1D")
		)
		(pad "2" smd rect
			(at -0.2667 0 270)
			(size 0.3048 0.381)
			(layers "B.Cu" "B.Mask" "B.Paste")
			(net "GND")
		)
	)
)
